# S9S_MB_2U (Grand Teton) — schematic netlist excerpt (pin names and nets, part order shuffled) for the footprints in the layout excerpt that follows; sources: Cadence DE-HDL packaged netlist, KiCad conversion of 03242023_DA0F0TMBIJ0_F0T_Motherboard_J_brd_V01_OCP.brd

R2566  Q_RES  0 5% CHIP  pkg 0402LF  page 231 : A = SMB_FRU_3V3AUX_SDA_R ; B = SMB_FRU_3V3AUX_SDA
R2986  Q_RES  0 5% EMPTY  pkg 0402LF  page 234 : A = SMB_2_BMC_GPU_R_SCL ; B = SMB_2_BMC_GPU_BUF_R_SCL

(kicad_pcb
	(version 20260206)
	(generator "pcbnew")
	(generator_version "10.0")
	(general
		(thickness 1.6)
		(legacy_teardrops no)
	)
	(paper "A4")
	(title_block
		(title "03242023_DA0F0TMBIJ0_F0T_Motherboard_J_brd_V01_OCP.brd")
		(comment 1 "Grand Teton / footprints 2380-2381 of 6105")
	)
	(layers
		(0 "F.Cu" signal "TOP")
		(4 "In1.Cu" signal "GND")
		(6 "In2.Cu" signal "IN1")
		(8 "In3.Cu" signal "GND1")
		(10 "In4.Cu" signal "IN2")
		(12 "In5.Cu" signal "GND2")
		(14 "In6.Cu" signal "IN3")
		(16 "In7.Cu" signal "GND3")
		(18 "In8.Cu" signal "VCC")
		(20 "In9.Cu" signal "VCC1")
		(22 "In10.Cu" signal "GND4")
		(24 "In11.Cu" signal "IN4")
		(26 "In12.Cu" signal "GND5")
		(28 "In13.Cu" signal "IN5")
		(30 "In14.Cu" signal "GND6")
		(32 "In15.Cu" signal "IN6")
		(34 "In16.Cu" signal "GND7")
		(2 "B.Cu" signal "BOTTOM")
		(9 "F.Adhes" user "F.Adhesive")
		(11 "B.Adhes" user "B.Adhesive")
		(13 "F.Paste" user "Package Geometry/Pastemask Top")
		(15 "B.Paste" user "Package Geometry/Pastemask Bottom")
		(5 "F.SilkS" user "Ref Des/Silkscreen Top")
		(7 "B.SilkS" user "Ref Des/Silkscreen Bottom")
		(1 "F.Mask" user "Board Geometry/Soldermask Top")
		(3 "B.Mask" user "Board Geometry/Soldermask Bottom")
		(17 "Dwgs.User" user "User.Drawings")
		(19 "Cmts.User" user "User.Comments")
		(21 "Eco1.User" user "User.Eco1")
		(23 "Eco2.User" user "User.Eco2")
		(25 "Edge.Cuts" user "Board Geometry/Outline")
		(27 "Margin" user)
		(31 "F.CrtYd" user "Package Geometry/Place Bound Top")
		(29 "B.CrtYd" user "Package Geometry/Place Bound Bottom")
		(35 "F.Fab" user "Ref Des/Assembly Top")
		(33 "B.Fab" user "Ref Des/Assembly Bottom")
	)
	(footprint ""
		(layer "F.Cu")
		(at 128.401572 -131.018026)
		(property "Reference" "R2566"
			(at 0 0 0)
			(layer "F.SilkS")
			(hide yes)
			(effects
				(font
					(size 1.27 1.27)
				)
			)
		)
		(property "Value" ""
			(at 0 0 0)
			(layer "F.Fab")
			(effects
				(font
					(size 1.27 1.27)
				)
			)
		)
		(duplicate_pad_numbers_are_jumpers no)
		(fp_line
			(start -0.7874 -0.4064)
			(end 0.7874 -0.4064)
			(stroke
				(width 0.1524)
				(type default)
			)
			(layer "F.SilkS")
		)
		(fp_line
			(start -0.7874 0.4064)
			(end -0.7874 -0.4064)
			(stroke
				(width 0.1524)
				(type default)
			)
			(layer "F.SilkS")
		)
		(fp_line
			(start 0.7874 -0.4064)
			(end 0.7874 0.4064)
			(stroke
				(width 0.1524)
				(type default)
			)
			(layer "F.SilkS")
		)
		(fp_line
			(start 0.7874 0.4064)
			(end -0.7874 0.4064)
			(stroke
				(width 0.1524)
				(type default)
			)
			(layer "F.SilkS")
		)
		(fp_line
			(start -0.67945 -0.305054)
			(end -0.12065 -0.305054)
			(stroke
				(width 0.1)
				(type default)
			)
			(layer "F.Fab")
		)
		(fp_line
			(start -0.67945 0.3048)
			(end -0.67945 -0.305054)
			(stroke
				(width 0.1)
				(type default)
			)
			(layer "F.Fab")
		)
		(fp_line
			(start -0.12065 -0.305054)
			(end -0.12065 -0.2794)
			(stroke
				(width 0.1)
				(type default)
			)
			(layer "F.Fab")
		)
		(fp_line
			(start -0.12065 -0.2794)
			(end 0.12065 -0.2794)
			(stroke
				(width 0.1)
				(type default)
			)
			(layer "F.Fab")
		)
		(fp_line
			(start -0.12065 0.2794)
			(end -0.12065 0.3048)
			(stroke
				(width 0.1)
				(type default)
			)
			(layer "F.Fab")
		)
		(fp_line
			(start -0.12065 0.3048)
			(end -0.67945 0.3048)
			(stroke
				(width 0.1)
				(type default)
			)
			(layer "F.Fab")
		)
		(fp_line
			(start 0.120396 0.2794)
			(end -0.12065 0.2794)
			(stroke
				(width 0.1)
				(type default)
			)
			(layer "F.Fab")
		)
		(fp_line
			(start 0.120396 0.3048)
			(end 0.120396 0.2794)
			(stroke
				(width 0.1)
				(type default)
			)
			(layer "F.Fab")
		)
		(fp_line
			(start 0.12065 -0.3048)
			(end 0.67945 -0.3048)
			(stroke
				(width 0.1)
				(type default)
			)
			(layer "F.Fab")
		)
		(fp_line
			(start 0.12065 -0.2794)
			(end 0.12065 -0.3048)
			(stroke
				(width 0.1)
				(type default)
			)
			(layer "F.Fab")
		)
		(fp_line
			(start 0.67945 -0.3048)
			(end 0.67945 0.3048)
			(stroke
				(width 0.1)
				(type default)
			)
			(layer "F.Fab")
		)
		(fp_line
			(start 0.67945 0.3048)
			(end 0.120396 0.3048)
			(stroke
				(width 0.1)
				(type default)
			)
			(layer "F.Fab")
		)
		(pad "1" smd circle
			(at -0.40005 0)
			(size 0 0)
			(layers "F.Cu" "F.Mask" "F.Paste")
			(net "SMB_FRU_3V3AUX_SDA_R")
		)
		(pad "2" smd circle
			(at 0.40005 0)
			(size 0 0)
			(layers "F.Cu" "F.Mask" "F.Paste")
			(net "SMB_FRU_3V3AUX_SDA")
		)
	)
	(footprint ""
		(layer "F.Cu")
		(at 44.467018 -439.824368 -90)
		(property "Reference" "R2986"
			(at 0 0 270)
			(layer "F.SilkS")
			(hide yes)
			(effects
				(font
					(size 1.27 1.27)
				)
			)
		)
		(property "Value" ""
			(at 0 0 270)
			(layer "F.Fab")
			(effects
				(font
					(size 1.27 1.27)
				)
			)
		)
		(duplicate_pad_numbers_are_jumpers no)
		(fp_line
			(start -0.7874 0.4064)
			(end -0.7874 -0.4064)
			(stroke
				(width 0.1524)
				(type default)
			)
			(layer "F.SilkS")
		)
		(fp_line
			(start 0.7874 0.4064)
			(end -0.7874 0.4064)
			(stroke
				(width 0.1524)
				(type default)
			)
			(layer "F.SilkS")
		)
		(fp_line
			(start -0.7874 -0.4064)
			(end 0.7874 -0.4064)
			(stroke
				(width 0.1524)
				(type default)
			)
			(layer "F.SilkS")
		)
		(fp_line
			(start 0.7874 -0.4064)
			(end 0.7874 0.4064)
			(stroke
				(width 0.1524)
				(type default)
			)
			(layer "F.SilkS")
		)
		(fp_line
			(start -0.67945 0.3048)
			(end -0.67945 -0.305054)
			(stroke
				(width 0.1)
				(type default)
			)
			(layer "F.Fab")
		)
		(fp_line
			(start -0.12065 0.3048)
			(end -0.67945 0.3048)
			(stroke
				(width 0.1)
				(type default)
			)
			(layer "F.Fab")
		)
		(fp_line
			(start 0.120396 0.3048)
			(end 0.120396 0.2794)
			(stroke
				(width 0.1)
				(type default)
			)
			(layer "F.Fab")
		)
		(fp_line
			(start 0.67945 0.3048)
			(end 0.120396 0.3048)
			(stroke
				(width 0.1)
				(type default)
			)
			(layer "F.Fab")
		)
		(fp_line
			(start -0.12065 0.2794)
			(end -0.12065 0.3048)
			(stroke
				(width 0.1)
				(type default)
			)
			(layer "F.Fab")
		)
		(fp_line
			(start 0.120396 0.2794)
			(end -0.12065 0.2794)
			(stroke
				(width 0.1)
				(type default)
			)
			(layer "F.Fab")
		)
		(fp_line
			(start -0.12065 -0.2794)
			(end 0.12065 -0.2794)
			(stroke
				(width 0.1)
				(type default)
			)
			(layer "F.Fab")
		)
		(fp_line
			(start 0.12065 -0.2794)
			(end 0.12065 -0.3048)
			(stroke
				(width 0.1)
				(type default)
			)
			(layer "F.Fab")
		)
		(fp_line
			(start 0.12065 -0.3048)
			(end 0.67945 -0.3048)
			(stroke
				(width 0.1)
				(type default)
			)
			(layer "F.Fab")
		)
		(fp_line
			(start 0.67945 -0.3048)
			(end 0.67945 0.3048)
			(stroke
				(width 0.1)
				(type default)
			)
			(layer "F.Fab")
		)
		(fp_line
			(start -0.67945 -0.305054)
			(end -0.12065 -0.305054)
			(stroke
				(width 0.1)
				(type default)
			)
			(layer "F.Fab")
		)
		(fp_line
			(start -0.12065 -0.305054)
			(end -0.12065 -0.2794)
			(stroke
				(width 0.1)
				(type default)
			)
			(layer "F.Fab")
		)
		(pad "1" smd circle
			(at -0.40005 0 270)
			(size 0 0)
			(layers "F.Cu" "F.Mask" "F.Paste")
			(net "SMB_2_BMC_GPU_R_SCL")
		)
		(pad "2" smd circle
			(at 0.40005 0 270)
			(size 0 0)
			(layers "F.Cu" "F.Mask" "F.Paste")
			(net "SMB_2_BMC_GPU_BUF_R_SCL")
		)
	)
)
